# S9S_MB_2U (Grand Teton) — schematic netlist excerpt (pin names and nets, part order shuffled) for the footprints in the layout excerpt that follows; sources: Cadence DE-HDL packaged netlist, KiCad conversion of 03242023_DA0F0TMBIJ0_F0T_Motherboard_J_brd_V01_OCP.brd

PR3337  Q_RES  0 5% CHIP  pkg 0402LF  page 258 : A = P5V_AUX_MODE ; B = GND
C2078  Q_CAP_DIFFBUS  DIFF BUS_0.22UF 6.3V 20% X6S  pkg C0201  page 181 : \1\ = P3E_PCH_BMC_TX_DN ; \2\ = P3E_PCH_BMC_TX_C_DN

(kicad_pcb
	(version 20260206)
	(generator "pcbnew")
	(generator_version "10.0")
	(general
		(thickness 1.6)
		(legacy_teardrops no)
	)
	(paper "A4")
	(title_block
		(title "03242023_DA0F0TMBIJ0_F0T_Motherboard_J_brd_V01_OCP.brd")
		(comment 1 "Grand Teton / footprints 5543-5544 of 6105")
	)
	(layers
		(0 "F.Cu" signal "TOP")
		(4 "In1.Cu" signal "GND")
		(6 "In2.Cu" signal "IN1")
		(8 "In3.Cu" signal "GND1")
		(10 "In4.Cu" signal "IN2")
		(12 "In5.Cu" signal "GND2")
		(14 "In6.Cu" signal "IN3")
		(16 "In7.Cu" signal "GND3")
		(18 "In8.Cu" signal "VCC")
		(20 "In9.Cu" signal "VCC1")
		(22 "In10.Cu" signal "GND4")
		(24 "In11.Cu" signal "IN4")
		(26 "In12.Cu" signal "GND5")
		(28 "In13.Cu" signal "IN5")
		(30 "In14.Cu" signal "GND6")
		(32 "In15.Cu" signal "IN6")
		(34 "In16.Cu" signal "GND7")
		(2 "B.Cu" signal "BOTTOM")
		(9 "F.Adhes" user "F.Adhesive")
		(11 "B.Adhes" user "B.Adhesive")
		(13 "F.Paste" user "Package Geometry/Pastemask Top")
		(15 "B.Paste" user "Package Geometry/Pastemask Bottom")
		(5 "F.SilkS" user "Ref Des/Silkscreen Top")
		(7 "B.SilkS" user "Ref Des/Silkscreen Bottom")
		(1 "F.Mask" user "Board Geometry/Soldermask Top")
		(3 "B.Mask" user "Board Geometry/Soldermask Bottom")
		(17 "Dwgs.User" user "User.Drawings")
		(19 "Cmts.User" user "User.Comments")
		(21 "Eco1.User" user "User.Eco1")
		(23 "Eco2.User" user "User.Eco2")
		(25 "Edge.Cuts" user "Board Geometry/Outline")
		(27 "Margin" user)
		(31 "F.CrtYd" user "Package Geometry/Place Bound Top")
		(29 "B.CrtYd" user "Package Geometry/Place Bound Bottom")
		(35 "F.Fab" user "Ref Des/Assembly Top")
		(33 "B.Fab" user "Ref Des/Assembly Bottom")
	)
	(footprint ""
		(layer "B.Cu")
		(at 455.66838 -382.435608)
		(property "Reference" "PR3337"
			(at 0 0 0)
			(layer "B.SilkS")
			(hide yes)
			(effects
				(font
					(size 1.27 1.27)
				)
				(justify mirror)
			)
		)
		(property "Value" ""
			(at 0 0 0)
			(layer "B.Fab")
			(effects
				(font
					(size 1.27 1.27)
				)
				(justify mirror)
			)
		)
		(duplicate_pad_numbers_are_jumpers no)
		(fp_line
			(start -0.7874 -0.4064)
			(end -0.7874 0.4064)
			(stroke
				(width 0.1524)
				(type default)
			)
			(layer "B.SilkS")
		)
		(fp_line
			(start -0.7874 0.4064)
			(end 0.7874 0.4064)
			(stroke
				(width 0.1524)
				(type default)
			)
			(layer "B.SilkS")
		)
		(fp_line
			(start 0.7874 -0.4064)
			(end -0.7874 -0.4064)
			(stroke
				(width 0.1524)
				(type default)
			)
			(layer "B.SilkS")
		)
		(fp_line
			(start 0.7874 0.4064)
			(end 0.7874 -0.4064)
			(stroke
				(width 0.1524)
				(type default)
			)
			(layer "B.SilkS")
		)
		(fp_line
			(start -0.67945 -0.3048)
			(end -0.67945 0.3048)
			(stroke
				(width 0.1)
				(type default)
			)
			(layer "B.Fab")
		)
		(fp_line
			(start -0.67945 0.3048)
			(end -0.120396 0.3048)
			(stroke
				(width 0.1)
				(type default)
			)
			(layer "B.Fab")
		)
		(fp_line
			(start -0.12065 -0.3048)
			(end -0.67945 -0.3048)
			(stroke
				(width 0.1)
				(type default)
			)
			(layer "B.Fab")
		)
		(fp_line
			(start -0.12065 -0.2794)
			(end -0.12065 -0.3048)
			(stroke
				(width 0.1)
				(type default)
			)
			(layer "B.Fab")
		)
		(fp_line
			(start -0.120396 0.2794)
			(end 0.12065 0.2794)
			(stroke
				(width 0.1)
				(type default)
			)
			(layer "B.Fab")
		)
		(fp_line
			(start -0.120396 0.3048)
			(end -0.120396 0.2794)
			(stroke
				(width 0.1)
				(type default)
			)
			(layer "B.Fab")
		)
		(fp_line
			(start 0.12065 -0.305054)
			(end 0.12065 -0.2794)
			(stroke
				(width 0.1)
				(type default)
			)
			(layer "B.Fab")
		)
		(fp_line
			(start 0.12065 -0.2794)
			(end -0.12065 -0.2794)
			(stroke
				(width 0.1)
				(type default)
			)
			(layer "B.Fab")
		)
		(fp_line
			(start 0.12065 0.2794)
			(end 0.12065 0.3048)
			(stroke
				(width 0.1)
				(type default)
			)
			(layer "B.Fab")
		)
		(fp_line
			(start 0.12065 0.3048)
			(end 0.67945 0.3048)
			(stroke
				(width 0.1)
				(type default)
			)
			(layer "B.Fab")
		)
		(fp_line
			(start 0.67945 -0.305054)
			(end 0.12065 -0.305054)
			(stroke
				(width 0.1)
				(type default)
			)
			(layer "B.Fab")
		)
		(fp_line
			(start 0.67945 0.3048)
			(end 0.67945 -0.305054)
			(stroke
				(width 0.1)
				(type default)
			)
			(layer "B.Fab")
		)
		(pad "1" smd circle
			(at 0.40005 0 180)
			(size 0 0)
			(layers "B.Cu" "B.Mask" "B.Paste")
			(net "P5V_AUX_MODE")
		)
		(pad "2" smd circle
			(at -0.40005 0 180)
			(size 0 0)
			(layers "B.Cu" "B.Mask" "B.Paste")
			(net "GND")
		)
	)
	(footprint ""
		(layer "B.Cu")
		(at 168.544494 -9.457944 -90)
		(property "Reference" "C2078"
			(at 0 0 90)
			(layer "B.SilkS")
			(hide yes)
			(effects
				(font
					(size 1.27 1.27)
				)
				(justify mirror)
			)
		)
		(property "Value" ""
			(at 0 0 90)
			(layer "B.Fab")
			(effects
				(font
					(size 1.27 1.27)
				)
				(justify mirror)
			)
		)
		(duplicate_pad_numbers_are_jumpers no)
		(fp_line
			(start -0.299974 0.150114)
			(end 0.299974 0.150114)
			(stroke
				(width 0.1)
				(type default)
			)
			(layer "B.Fab")
		)
		(fp_line
			(start 0.299974 0.150114)
			(end 0.299974 -0.150114)
			(stroke
				(width 0.1)
				(type default)
			)
			(layer "B.Fab")
		)
		(fp_line
			(start -0.299974 -0.150114)
			(end -0.299974 0.150114)
			(stroke
				(width 0.1)
				(type default)
			)
			(layer "B.Fab")
		)
		(fp_line
			(start 0.299974 -0.150114)
			(end -0.299974 -0.150114)
			(stroke
				(width 0.1)
				(type default)
			)
			(layer "B.Fab")
		)
		(pad "1" smd rect
			(at 0.2667 0 90)
			(size 0.3048 0.381)
			(layers "B.Cu" "B.Mask" "B.Paste")
			(net "P3E_PCH_BMC_TX_DN")
		)
		(pad "2" smd rect
			(at -0.2667 0 90)
			(size 0.3048 0.381)
			(layers "B.Cu" "B.Mask" "B.Paste")
			(net "P3E_PCH_BMC_TX_C_DN")
		)
		(zone
			(layer "In16.Cu")
			(hatch none 0.5)
			(connect_pads
				(clearance 0)
			)
			(min_thickness 0.25)
			(keepout
				(tracks not_allowed)
				(vias allowed)
				(pads allowed)
				(copperpour not_allowed)
				(footprints allowed)
			)
			(placement
				(enabled no)
				(sheetname "")
			)
			(fill
				(thermal_gap 0.5)
				(thermal_bridge_width 0.5)
				(island_removal_mode 0)
			)
			(polygon
				(pts
					(xy 168.303194 -9.521444) (xy 168.785794 -9.521444) (xy 168.785794 -9.927844) (xy 168.303194 -9.927844)
				)
			)
		)
		(zone
			(layer "In16.Cu")
			(hatch none 0.5)
			(connect_pads
				(clearance 0)
			)
			(min_thickness 0.25)
			(keepout
				(tracks not_allowed)
				(vias allowed)
				(pads allowed)
				(copperpour not_allowed)
				(footprints allowed)
			)
			(placement
				(enabled no)
				(sheetname "")
			)
			(fill
				(thermal_gap 0.5)
				(thermal_bridge_width 0.5)
				(island_removal_mode 0)
			)
			(polygon
				(pts
					(xy 168.303194 -8.988044) (xy 168.785794 -8.988044) (xy 168.785794 -9.394444) (xy 168.303194 -9.394444)
				)
			)
		)
	)
)
